# BASEBOARD_FAB2 (Tioga Pass) — schematic netlist excerpt (pin names and nets, part order shuffled) for the footprints in the layout excerpt that follows; sources: Cadence DE-HDL packaged netlist, KiCad conversion of Wiwynn_Tioga_Pass_MB.brd

U8F2  W25Q128  IC  pkg SKT16  page 162
  HOLD_N_IO(3)  = PU_SPI_BMC_BT_HOLD_N
  VCC  = P3V3_STBY
  RESET_N  = PU_SPI_FLASH_RESET_2_N
  NC(0)  = TP_SPI_2_0
  NC(1)  = TP_SPI_2_1
  NC(2)  = TP_SPI_2_2
  CS_N  = SPI_BMC_BT_CS_N
  DO_IO(1)  = SPI_BMC_BT_DI_R
  WP_N_IO(2)  = PU_SPI_BMC_BT_WP_N
  GND  = GND
  NC(3)  = TP_SPI_2_3
  NC(4)  = TP_SPI_2_4
  NC(5)  = TP_SPI_2_5
  NC(6)  = TP_SPI_2_6
  DI_IO(0)  = SPI_BMC_BT_DO
  CLK  = SPI_BMC_BT_CLK

(kicad_pcb
	(version 20260206)
	(generator "pcbnew")
	(generator_version "10.0")
	(general
		(thickness 1.6)
		(legacy_teardrops no)
	)
	(paper "A4")
	(title_block
		(title "Wiwynn_Tioga_Pass_MB.brd")
		(comment 1 "Tioga Pass / footprints 1700-1700 of 4770")
	)
	(layers
		(0 "F.Cu" signal "TOP")
		(4 "In1.Cu" signal "L2GND")
		(6 "In2.Cu" signal "L3")
		(8 "In3.Cu" signal "L4GND")
		(10 "In4.Cu" signal "L5")
		(12 "In5.Cu" signal "L6GND")
		(14 "In6.Cu" signal "L7VCC")
		(16 "In7.Cu" signal "L8VCC")
		(18 "In8.Cu" signal "L9GND")
		(20 "In9.Cu" signal "L10")
		(22 "In10.Cu" signal "L11GND")
		(24 "In11.Cu" signal "L12")
		(26 "In12.Cu" signal "L13GND")
		(2 "B.Cu" signal "BOTTOM")
		(9 "F.Adhes" user "F.Adhesive")
		(11 "B.Adhes" user "B.Adhesive")
		(13 "F.Paste" user "Package Geometry/Pastemask Top")
		(15 "B.Paste" user "Package Geometry/Pastemask Bottom")
		(5 "F.SilkS" user "Ref Des/Silkscreen Top")
		(7 "B.SilkS" user "Ref Des/Silkscreen Bottom")
		(1 "F.Mask" user "Board Geometry/Soldermask Top")
		(3 "B.Mask" user "Board Geometry/Soldermask Bottom")
		(17 "Dwgs.User" user "User.Drawings")
		(19 "Cmts.User" user "User.Comments")
		(21 "Eco1.User" user "User.Eco1")
		(23 "Eco2.User" user "User.Eco2")
		(25 "Edge.Cuts" user "Board Geometry/Outline")
		(27 "Margin" user)
		(31 "F.CrtYd" user "Package Geometry/Place Bound Top")
		(29 "B.CrtYd" user "Package Geometry/Place Bound Bottom")
		(35 "F.Fab" user "Ref Des/Assembly Top")
		(33 "B.Fab" user "Ref Des/Assembly Bottom")
	)
	(footprint ""
		(layer "F.Cu")
		(at 367.088928 -45.23232)
		(property "Reference" "U8F2"
			(at 10.3505 -2.88671 180)
			(unlocked yes)
			(layer "F.SilkS")
			(effects
				(font
					(size 0.7874 0.5842)
					(thickness 0.1524)
				)
				(justify left)
			)
		)
		(property "Value" ""
			(at 0 0 0)
			(layer "F.Fab")
			(effects
				(font
					(size 1.27 1.27)
				)
			)
		)
		(duplicate_pad_numbers_are_jumpers no)
		(fp_line
			(start -2.094738 -1.929892)
			(end 11.645392 -1.929892)
			(stroke
				(width 0.1524)
				(type default)
			)
			(layer "F.SilkS")
		)
		(fp_line
			(start -2.094738 10.819892)
			(end -2.094738 -1.929892)
			(stroke
				(width 0.1524)
				(type default)
			)
			(layer "F.SilkS")
		)
		(fp_line
			(start 11.645392 -1.929892)
			(end 11.645392 10.819892)
			(stroke
				(width 0.1524)
				(type default)
			)
			(layer "F.SilkS")
		)
		(fp_line
			(start 11.645392 10.819892)
			(end -2.094738 10.819892)
			(stroke
				(width 0.1524)
				(type default)
			)
			(layer "F.SilkS")
		)
		(fp_circle
			(center -2.568194 -2.286)
			(end -2.441194 -2.286)
			(stroke
				(width 0.762)
				(type default)
			)
			(fill no)
			(layer "F.SilkS")
		)
		(fp_rect
			(start -5.600954 12.260326)
			(end -2.094738 -3.284474)
			(stroke
				(width 0)
				(type default)
			)
			(fill no)
			(layer "F.CrtYd")
		)
		(fp_rect
			(start 11.645392 12.260326)
			(end 15.404846 -3.284474)
			(stroke
				(width 0)
				(type default)
			)
			(fill no)
			(layer "F.CrtYd")
		)
		(fp_poly
			(pts
				(xy -2.094738 10.819892) (xy 11.645392 10.819892) (xy 11.645392 -1.929892) (xy -2.094738 -1.929892)
			)
			(stroke
				(width 0)
				(type default)
			)
			(fill no)
			(layer "F.CrtYd")
		)
		(fp_poly
			(pts
				(xy 2.029968 -1.929892) (xy 2.629916 -3.32994) (xy 6.970014 -3.32994) (xy 7.569962 -1.929892)
			)
			(stroke
				(width 0)
				(type default)
			)
			(fill no)
			(layer "F.CrtYd")
		)
		(fp_poly
			(pts
				(xy 7.569962 10.819892) (xy 6.970014 12.21994) (xy 2.629916 12.21994) (xy 2.029968 10.819892)
			)
			(stroke
				(width 0)
				(type default)
			)
			(fill no)
			(layer "F.CrtYd")
		)
		(fp_line
			(start -2.094738 -1.929892)
			(end 11.645392 -1.929892)
			(stroke
				(width 0.1)
				(type default)
			)
			(layer "F.Fab")
		)
		(fp_line
			(start -2.094738 10.819892)
			(end -2.094738 -1.929892)
			(stroke
				(width 0.1)
				(type default)
			)
			(layer "F.Fab")
		)
		(fp_line
			(start 2.029968 -1.929892)
			(end 2.629916 -3.32994)
			(stroke
				(width 0.1)
				(type default)
			)
			(layer "F.Fab")
		)
		(fp_line
			(start 2.629916 -3.32994)
			(end 6.970014 -3.32994)
			(stroke
				(width 0.1)
				(type default)
			)
			(layer "F.Fab")
		)
		(fp_line
			(start 2.629916 12.21994)
			(end 2.029968 10.819892)
			(stroke
				(width 0.1)
				(type default)
			)
			(layer "F.Fab")
		)
		(fp_line
			(start 6.970014 -3.32994)
			(end 7.569962 -1.929892)
			(stroke
				(width 0.1)
				(type default)
			)
			(layer "F.Fab")
		)
		(fp_line
			(start 6.970014 12.21994)
			(end 2.629916 12.21994)
			(stroke
				(width 0.1)
				(type default)
			)
			(layer "F.Fab")
		)
		(fp_line
			(start 7.569962 10.819892)
			(end 6.970014 12.21994)
			(stroke
				(width 0.1)
				(type default)
			)
			(layer "F.Fab")
		)
		(fp_line
			(start 11.645392 -1.929892)
			(end 11.645392 10.819892)
			(stroke
				(width 0.1)
				(type default)
			)
			(layer "F.Fab")
		)
		(fp_line
			(start 11.645392 10.819892)
			(end -2.094738 10.819892)
			(stroke
				(width 0.1)
				(type default)
			)
			(layer "F.Fab")
		)
		(fp_circle
			(center -2.645918 -0.940054)
			(end -2.518918 -0.940054)
			(stroke
				(width 0.254)
				(type default)
			)
			(fill no)
			(layer "F.Fab")
		)
		(fp_text user "8"
			(at -1.498854 11.547348 90)
			(unlocked yes)
			(layer "F.SilkS")
			(effects
				(font
					(size 0.7874 0.5842)
					(thickness 0.1524)
				)
				(justify left)
			)
		)
		(fp_text user "9"
			(at 9.397746 11.529822 90)
			(unlocked yes)
			(layer "F.SilkS")
			(effects
				(font
					(size 0.7874 0.5842)
					(thickness 0.1524)
				)
				(justify left)
			)
		)
		(fp_text user "16"
			(at 12.40917 0.31496 90)
			(unlocked yes)
			(layer "F.SilkS")
			(effects
				(font
					(size 0.7874 0.5842)
					(thickness 0.1524)
				)
				(justify left)
			)
		)
		(fp_text user "8"
			(at -2.4257 9.04621 0)
			(unlocked yes)
			(layer "F.Fab")
			(effects
				(font
					(size 0.635 0.635)
					(thickness 0.1524)
				)
				(justify left)
			)
		)
		(fp_text user "16"
			(at 11.646916 0.367792 0)
			(unlocked yes)
			(layer "F.Fab")
			(effects
				(font
					(size 0.254 0.254)
					(thickness 0.000001)
				)
				(justify left)
			)
		)
		(fp_text user "9"
			(at 11.862054 9.20369 0)
			(unlocked yes)
			(layer "F.Fab")
			(effects
				(font
					(size 0.254 0.254)
					(thickness 0.000001)
				)
				(justify left)
			)
		)
		(pad "1" smd rect
			(at 0 0)
			(size 1.9304 0.635)
			(layers "F.Cu" "F.Mask" "F.Paste")
			(net "PU_SPI_BMC_BT_HOLD_N")
		)
		(pad "2" smd rect
			(at 0 1.27)
			(size 1.9304 0.635)
			(layers "F.Cu" "F.Mask" "F.Paste")
			(net "P3V3_STBY")
		)
		(pad "3" smd rect
			(at 0 2.54)
			(size 1.9304 0.635)
			(layers "F.Cu" "F.Mask" "F.Paste")
			(net "PU_SPI_FLASH_RESET_2_N")
		)
		(pad "4" smd rect
			(at 0 3.81)
			(size 1.9304 0.635)
			(layers "F.Cu" "F.Mask" "F.Paste")
			(net "TP_SPI_2_0")
		)
		(pad "5" smd rect
			(at 0 5.08)
			(size 1.9304 0.635)
			(layers "F.Cu" "F.Mask" "F.Paste")
			(net "TP_SPI_2_1")
		)
		(pad "6" smd rect
			(at 0 6.35)
			(size 1.9304 0.635)
			(layers "F.Cu" "F.Mask" "F.Paste")
			(net "TP_SPI_2_2")
		)
		(pad "7" smd rect
			(at 0 7.62)
			(size 1.9304 0.635)
			(layers "F.Cu" "F.Mask" "F.Paste")
			(net "SPI_BMC_BT_CS_N")
		)
		(pad "8" smd rect
			(at 0 8.89)
			(size 1.9304 0.635)
			(layers "F.Cu" "F.Mask" "F.Paste")
			(net "SPI_BMC_BT_DI_R")
		)
		(pad "9" smd rect
			(at 9.5504 8.89)
			(size 1.9304 0.635)
			(layers "F.Cu" "F.Mask" "F.Paste")
			(net "PU_SPI_BMC_BT_WP_N")
		)
		(pad "10" smd rect
			(at 9.5504 7.62)
			(size 1.9304 0.635)
			(layers "F.Cu" "F.Mask" "F.Paste")
			(net "GND")
		)
		(pad "11" smd rect
			(at 9.5504 6.35)
			(size 1.9304 0.635)
			(layers "F.Cu" "F.Mask" "F.Paste")
			(net "TP_SPI_2_3")
		)
		(pad "12" smd rect
			(at 9.5504 5.08)
			(size 1.9304 0.635)
			(layers "F.Cu" "F.Mask" "F.Paste")
			(net "TP_SPI_2_4")
		)
		(pad "13" smd rect
			(at 9.5504 3.81)
			(size 1.9304 0.635)
			(layers "F.Cu" "F.Mask" "F.Paste")
			(net "TP_SPI_2_5")
		)
		(pad "14" smd rect
			(at 9.5504 2.54)
			(size 1.9304 0.635)
			(layers "F.Cu" "F.Mask" "F.Paste")
			(net "TP_SPI_2_6")
		)
		(pad "15" smd rect
			(at 9.5504 1.27)
			(size 1.9304 0.635)
			(layers "F.Cu" "F.Mask" "F.Paste")
			(net "SPI_BMC_BT_DO")
		)
		(pad "16" smd rect
			(at 9.5504 0)
			(size 1.9304 0.635)
			(layers "F.Cu" "F.Mask" "F.Paste")
			(net "SPI_BMC_BT_CLK")
		)
	)
)
